(kicad_pcb
	(version 20260206)
	(generator "pcbnew")
	(generator_version "10.0")
	(general
		(thickness 1.6)
		(legacy_teardrops no)
	)
	(paper "A4")
	(title_block
		(title "03242023_DA0F0TMBIJ0_F0T_Motherboard_J_brd_V01_OCP.brd")
		(comment 1 "Grand Teton / footprints 670-674 of 6105")
	)
	(layers
		(0 "F.Cu" signal "TOP")
		(4 "In1.Cu" signal "GND")
		(6 "In2.Cu" signal "IN1")
		(8 "In3.Cu" signal "GND1")
		(10 "In4.Cu" signal "IN2")
		(12 "In5.Cu" signal "GND2")
		(14 "In6.Cu" signal "IN3")
		(16 "In7.Cu" signal "GND3")
		(18 "In8.Cu" signal "VCC")
		(20 "In9.Cu" signal "VCC1")
		(22 "In10.Cu" signal "GND4")
		(24 "In11.Cu" signal "IN4")
		(26 "In12.Cu" signal "GND5")
		(28 "In13.Cu" signal "IN5")
		(30 "In14.Cu" signal "GND6")
		(32 "In15.Cu" signal "IN6")
		(34 "In16.Cu" signal "GND7")
		(2 "B.Cu" signal "BOTTOM")
		(9 "F.Adhes" user "F.Adhesive")
		(11 "B.Adhes" user "B.Adhesive")
		(13 "F.Paste" user "Package Geometry/Pastemask Top")
		(15 "B.Paste" user "Package Geometry/Pastemask Bottom")
		(5 "F.SilkS" user "Ref Des/Silkscreen Top")
		(7 "B.SilkS" user "Ref Des/Silkscreen Bottom")
		(1 "F.Mask" user "Board Geometry/Soldermask Top")
		(3 "B.Mask" user "Board Geometry/Soldermask Bottom")
		(17 "Dwgs.User" user "User.Drawings")
		(19 "Cmts.User" user "User.Comments")
		(21 "Eco1.User" user "User.Eco1")
		(23 "Eco2.User" user "User.Eco2")
		(25 "Edge.Cuts" user "Board Geometry/Outline")
		(27 "Margin" user)
		(31 "F.CrtYd" user "Package Geometry/Place Bound Top")
		(29 "B.CrtYd" user "Package Geometry/Place Bound Bottom")
		(35 "F.Fab" user "Ref Des/Assembly Top")
		(33 "B.Fab" user "Ref Des/Assembly Bottom")
	)
	(footprint ""
		(layer "F.Cu")
		(at 327.636378 -347.990922)
		(property "Reference" "PR133"
			(at 0 0 0)
			(layer "F.SilkS")
			(hide yes)
			(effects
				(font
					(size 1.27 1.27)
				)
			)
		)
		(property "Value" ""
			(at 0 0 0)
			(layer "F.Fab")
			(effects
				(font
					(size 1.27 1.27)
				)
			)
		)
		(duplicate_pad_numbers_are_jumpers no)
		(fp_line
			(start -0.7874 -0.4064)
			(end 0.7874 -0.4064)
			(stroke
				(width 0.1524)
				(type default)
			)
			(layer "F.SilkS")
		)
		(fp_line
			(start -0.7874 0.4064)
			(end -0.7874 -0.4064)
			(stroke
				(width 0.1524)
				(type default)
			)
			(layer "F.SilkS")
		)
		(fp_line
			(start 0.7874 -0.4064)
			(end 0.7874 0.4064)
			(stroke
				(width 0.1524)
				(type default)
			)
			(layer "F.SilkS")
		)
		(fp_line
			(start 0.7874 0.4064)
			(end -0.7874 0.4064)
			(stroke
				(width 0.1524)
				(type default)
			)
			(layer "F.SilkS")
		)
		(fp_line
			(start -0.67945 -0.305054)
			(end -0.12065 -0.305054)
			(stroke
				(width 0.1)
				(type default)
			)
			(layer "F.Fab")
		)
		(fp_line
			(start -0.67945 0.3048)
			(end -0.67945 -0.305054)
			(stroke
				(width 0.1)
				(type default)
			)
			(layer "F.Fab")
		)
		(fp_line
			(start -0.12065 -0.305054)
			(end -0.12065 -0.2794)
			(stroke
				(width 0.1)
				(type default)
			)
			(layer "F.Fab")
		)
		(fp_line
			(start -0.12065 -0.2794)
			(end 0.12065 -0.2794)
			(stroke
				(width 0.1)
				(type default)
			)
			(layer "F.Fab")
		)
		(fp_line
			(start -0.12065 0.2794)
			(end -0.12065 0.3048)
			(stroke
				(width 0.1)
				(type default)
			)
			(layer "F.Fab")
		)
		(fp_line
			(start -0.12065 0.3048)
			(end -0.67945 0.3048)
			(stroke
				(width 0.1)
				(type default)
			)
			(layer "F.Fab")
		)
		(fp_line
			(start 0.120396 0.2794)
			(end -0.12065 0.2794)
			(stroke
				(width 0.1)
				(type default)
			)
			(layer "F.Fab")
		)
		(fp_line
			(start 0.120396 0.3048)
			(end 0.120396 0.2794)
			(stroke
				(width 0.1)
				(type default)
			)
			(layer "F.Fab")
		)
		(fp_line
			(start 0.12065 -0.3048)
			(end 0.67945 -0.3048)
			(stroke
				(width 0.1)
				(type default)
			)
			(layer "F.Fab")
		)
		(fp_line
			(start 0.12065 -0.2794)
			(end 0.12065 -0.3048)
			(stroke
				(width 0.1)
				(type default)
			)
			(layer "F.Fab")
		)
		(fp_line
			(start 0.67945 -0.3048)
			(end 0.67945 0.3048)
			(stroke
				(width 0.1)
				(type default)
			)
			(layer "F.Fab")
		)
		(fp_line
			(start 0.67945 0.3048)
			(end 0.120396 0.3048)
			(stroke
				(width 0.1)
				(type default)
			)
			(layer "F.Fab")
		)
		(pad "1" smd circle
			(at -0.40005 0)
			(size 0 0)
			(layers "F.Cu" "F.Mask" "F.Paste")
			(net "PVCCIN_CPU0_LSET7")
		)
		(pad "2" smd circle
			(at 0.40005 0)
			(size 0 0)
			(layers "F.Cu" "F.Mask" "F.Paste")
			(net "GND")
		)
	)
	(footprint ""
		(layer "F.Cu")
		(at 20.11426 -164.737796)
		(property "Reference" "C1336"
			(at 0 0 0)
			(layer "F.SilkS")
			(hide yes)
			(effects
				(font
					(size 1.27 1.27)
				)
			)
		)
		(property "Value" ""
			(at 0 0 0)
			(layer "F.Fab")
			(effects
				(font
					(size 1.27 1.27)
				)
			)
		)
		(duplicate_pad_numbers_are_jumpers no)
		(fp_line
			(start -0.7874 -0.4064)
			(end 0.7874 -0.4064)
			(stroke
				(width 0.1524)
				(type default)
			)
			(layer "F.SilkS")
		)
		(fp_line
			(start -0.7874 0.4064)
			(end -0.7874 -0.4064)
			(stroke
				(width 0.1524)
				(type default)
			)
			(layer "F.SilkS")
		)
		(fp_line
			(start 0.7874 -0.4064)
			(end 0.7874 0.4064)
			(stroke
				(width 0.1524)
				(type default)
			)
			(layer "F.SilkS")
		)
		(fp_line
			(start 0.7874 0.4064)
			(end -0.7874 0.4064)
			(stroke
				(width 0.1524)
				(type default)
			)
			(layer "F.SilkS")
		)
		(fp_line
			(start -0.67945 -0.305054)
			(end -0.12065 -0.305054)
			(stroke
				(width 0.1)
				(type default)
			)
			(layer "F.Fab")
		)
		(fp_line
			(start -0.67945 0.3048)
			(end -0.67945 -0.305054)
			(stroke
				(width 0.1)
				(type default)
			)
			(layer "F.Fab")
		)
		(fp_line
			(start -0.12065 -0.305054)
			(end -0.12065 -0.2794)
			(stroke
				(width 0.1)
				(type default)
			)
			(layer "F.Fab")
		)
		(fp_line
			(start -0.12065 -0.2794)
			(end 0.12065 -0.2794)
			(stroke
				(width 0.1)
				(type default)
			)
			(layer "F.Fab")
		)
		(fp_line
			(start -0.12065 0.2794)
			(end -0.12065 0.3048)
			(stroke
				(width 0.1)
				(type default)
			)
			(layer "F.Fab")
		)
		(fp_line
			(start -0.12065 0.3048)
			(end -0.67945 0.3048)
			(stroke
				(width 0.1)
				(type default)
			)
			(layer "F.Fab")
		)
		(fp_line
			(start 0.120396 0.2794)
			(end -0.12065 0.2794)
			(stroke
				(width 0.1)
				(type default)
			)
			(layer "F.Fab")
		)
		(fp_line
			(start 0.120396 0.3048)
			(end 0.120396 0.2794)
			(stroke
				(width 0.1)
				(type default)
			)
			(layer "F.Fab")
		)
		(fp_line
			(start 0.12065 -0.3048)
			(end 0.67945 -0.3048)
			(stroke
				(width 0.1)
				(type default)
			)
			(layer "F.Fab")
		)
		(fp_line
			(start 0.12065 -0.2794)
			(end 0.12065 -0.3048)
			(stroke
				(width 0.1)
				(type default)
			)
			(layer "F.Fab")
		)
		(fp_line
			(start 0.67945 -0.3048)
			(end 0.67945 0.3048)
			(stroke
				(width 0.1)
				(type default)
			)
			(layer "F.Fab")
		)
		(fp_line
			(start 0.67945 0.3048)
			(end 0.120396 0.3048)
			(stroke
				(width 0.1)
				(type default)
			)
			(layer "F.Fab")
		)
		(pad "1" smd circle
			(at -0.40005 0)
			(size 0 0)
			(layers "F.Cu" "F.Mask" "F.Paste")
			(net "PVNN_TERM_CPU1")
		)
		(pad "2" smd circle
			(at 0.40005 0)
			(size 0 0)
			(layers "F.Cu" "F.Mask" "F.Paste")
			(net "GND")
		)
	)
	(footprint ""
		(layer "F.Cu")
		(at 189.738762 -25.643332)
		(property "Reference" "PU300"
			(at -6.880352 -3.665982 0)
			(unlocked yes)
			(layer "F.SilkS")
			(effects
				(font
					(size 0.7874 0.5842)
					(thickness 0.1524)
				)
				(justify left)
			)
		)
		(property "Value" ""
			(at 0 0 0)
			(layer "F.Fab")
			(effects
				(font
					(size 1.27 1.27)
				)
			)
		)
		(duplicate_pad_numbers_are_jumpers no)
		(fp_line
			(start -1.774952 -1.039876)
			(end -1.774952 1.039876)
			(stroke
				(width 0.1524)
				(type default)
			)
			(layer "F.SilkS")
		)
		(fp_line
			(start -1.774952 1.039876)
			(end 1.774952 1.039876)
			(stroke
				(width 0.1524)
				(type default)
			)
			(layer "F.SilkS")
		)
		(fp_line
			(start 1.774952 -1.039876)
			(end -1.774952 -1.039876)
			(stroke
				(width 0.1524)
				(type default)
			)
			(layer "F.SilkS")
		)
		(fp_line
			(start 1.774952 1.039876)
			(end 1.774952 -1.039876)
			(stroke
				(width 0.1524)
				(type default)
			)
			(layer "F.SilkS")
		)
		(fp_poly
			(pts
				(xy -1.769872 -1.039876) (xy -1.769872 -0.249936) (xy -2.531872 -0.249936) (xy -2.531872 -1.801876)
				(xy -0.999998 -1.801876) (xy -0.999998 -1.039876)
			)
			(stroke
				(width 0)
				(type default)
			)
			(fill yes)
			(layer "F.SilkS")
		)
		(fp_line
			(start -1.769872 -1.039876)
			(end -1.769872 1.039876)
			(stroke
				(width 0.1)
				(type default)
			)
			(layer "F.Fab")
		)
		(fp_line
			(start -1.769872 1.039876)
			(end 1.769872 1.039876)
			(stroke
				(width 0.1)
				(type default)
			)
			(layer "F.Fab")
		)
		(fp_line
			(start 1.769872 -1.039876)
			(end -1.769872 -1.039876)
			(stroke
				(width 0.1)
				(type default)
			)
			(layer "F.Fab")
		)
		(fp_line
			(start 1.769872 1.039876)
			(end 1.769872 -1.039876)
			(stroke
				(width 0.1)
				(type default)
			)
			(layer "F.Fab")
		)
		(fp_poly
			(pts
				(xy -1.769872 -1.039876) (xy -0.999998 -1.039876) (xy -0.999998 -1.801876) (xy -2.531872 -1.801876)
				(xy -2.531872 -0.249936) (xy -1.769872 -0.249936)
			)
			(stroke
				(width 0)
				(type default)
			)
			(fill yes)
			(layer "F.Fab")
		)
		(pad "A1" smd circle
			(at -1.500124 -0.750062)
			(size 0.2286 0.2286)
			(layers "F.Cu" "F.Mask" "F.Paste")
			(net "P12V_SCM_SENSE")
		)
		(pad "A2" smd circle
			(at -0.999998 -0.750062)
			(size 0.2286 0.2286)
			(layers "F.Cu" "F.Mask" "F.Paste")
			(net "P12V_SCM_VCC")
		)
		(pad "A3" smd circle
			(at -0.499872 -0.750062)
			(size 0.2286 0.2286)
			(layers "F.Cu" "F.Mask" "F.Paste")
			(net "P12V_AUX")
		)
		(pad "A4" smd circle
			(at 0 -0.750062)
			(size 0.2286 0.2286)
			(layers "F.Cu" "F.Mask" "F.Paste")
			(net "P12V_SCM_R")
		)
		(pad "A5" smd circle
			(at 0.499872 -0.750062)
			(size 0.2286 0.2286)
			(layers "F.Cu" "F.Mask" "F.Paste")
			(net "P12V_AUX")
		)
		(pad "A6" smd circle
			(at 0.999998 -0.750062)
			(size 0.2286 0.2286)
			(layers "F.Cu" "F.Mask" "F.Paste")
			(net "P12V_SCM_GATE")
		)
		(pad "A7" smd circle
			(at 1.500124 -0.750062)
			(size 0.2286 0.2286)
			(layers "F.Cu" "F.Mask" "F.Paste")
			(net "GND")
		)
		(pad "B1" smd circle
			(at -1.500124 -0.249936)
			(size 0.2286 0.2286)
			(layers "F.Cu" "F.Mask" "F.Paste")
			(net "P12V_SCM_CB")
		)
		(pad "B2" smd circle
			(at -0.999998 -0.249936)
			(size 0.2286 0.2286)
			(layers "F.Cu" "F.Mask" "F.Paste")
			(net "GND")
		)
		(pad "B3" smd circle
			(at -0.499872 -0.249936)
			(size 0.2286 0.2286)
			(layers "F.Cu" "F.Mask" "F.Paste")
			(net "P12V_AUX")
		)
		(pad "B4" smd circle
			(at 0 -0.249936)
			(size 0.2286 0.2286)
			(layers "F.Cu" "F.Mask" "F.Paste")
			(net "P12V_SCM_R")
		)
		(pad "B5" smd circle
			(at 0.499872 -0.249936)
			(size 0.2286 0.2286)
			(layers "F.Cu" "F.Mask" "F.Paste")
			(net "P12V_AUX")
		)
		(pad "B6" smd circle
			(at 0.999998 -0.249936)
			(size 0.2286 0.2286)
			(layers "F.Cu" "F.Mask" "F.Paste")
			(net "P12V_SCM_R")
		)
		(pad "B7" smd circle
			(at 1.500124 -0.249936)
			(size 0.2286 0.2286)
			(layers "F.Cu" "F.Mask" "F.Paste")
			(net "GND")
		)
		(pad "C1" smd circle
			(at -1.500124 0.249936)
			(size 0.2286 0.2286)
			(layers "F.Cu" "F.Mask" "F.Paste")
			(net "GND")
		)
		(pad "C2" smd circle
			(at -0.999998 0.249936)
			(size 0.2286 0.2286)
			(layers "F.Cu" "F.Mask" "F.Paste")
			(net "GND")
		)
		(pad "C3" smd circle
			(at -0.499872 0.249936)
			(size 0.2286 0.2286)
			(layers "F.Cu" "F.Mask" "F.Paste")
			(net "P12V_AUX")
		)
		(pad "C4" smd circle
			(at 0 0.249936)
			(size 0.2286 0.2286)
			(layers "F.Cu" "F.Mask" "F.Paste")
			(net "P12V_SCM_R")
		)
		(pad "C5" smd circle
			(at 0.499872 0.249936)
			(size 0.2286 0.2286)
			(layers "F.Cu" "F.Mask" "F.Paste")
			(net "P12V_AUX")
		)
		(pad "C6" smd circle
			(at 0.999998 0.249936)
			(size 0.2286 0.2286)
			(layers "F.Cu" "F.Mask" "F.Paste")
			(net "P12V_SCM_R")
		)
		(pad "C7" smd circle
			(at 1.500124 0.249936)
			(size 0.2286 0.2286)
			(layers "F.Cu" "F.Mask" "F.Paste")
			(net "P12V_SCM_FAULT_N")
		)
		(pad "D1" smd circle
			(at -1.500124 0.750062)
			(size 0.2286 0.2286)
			(layers "F.Cu" "F.Mask" "F.Paste")
			(net "P12V_SCM_REG")
		)
		(pad "D2" smd circle
			(at -0.999998 0.750062)
			(size 0.2286 0.2286)
			(layers "F.Cu" "F.Mask" "F.Paste")
			(net "P12V_SCM_UV")
		)
		(pad "D3" smd circle
			(at -0.499872 0.750062)
			(size 0.2286 0.2286)
			(layers "F.Cu" "F.Mask" "F.Paste")
			(net "P12V_SCM_OV")
		)
		(pad "D4" smd circle
			(at 0 0.750062)
			(size 0.2286 0.2286)
			(layers "F.Cu" "F.Mask" "F.Paste")
			(net "P12V_SCM_R")
		)
		(pad "D5" smd circle
			(at 0.499872 0.750062)
			(size 0.2286 0.2286)
			(layers "F.Cu" "F.Mask" "F.Paste")
			(net "P12V_AUX")
		)
		(pad "D6" smd circle
			(at 0.999998 0.750062)
			(size 0.2286 0.2286)
			(layers "F.Cu" "F.Mask" "F.Paste")
			(net "P12V_SCM_R")
		)
		(pad "D7" smd circle
			(at 1.500124 0.750062)
			(size 0.2286 0.2286)
			(layers "F.Cu" "F.Mask" "F.Paste")
			(net "P12V_SCM_PWRGD")
		)
	)
	(footprint ""
		(layer "F.Cu")
		(at 193.38036 -118.074948)
		(property "Reference" "R1420"
			(at 0 0 0)
			(layer "F.SilkS")
			(hide yes)
			(effects
				(font
					(size 1.27 1.27)
				)
			)
		)
		(property "Value" ""
			(at 0 0 0)
			(layer "F.Fab")
			(effects
				(font
					(size 1.27 1.27)
				)
			)
		)
		(duplicate_pad_numbers_are_jumpers no)
		(fp_line
			(start -0.7874 -0.4064)
			(end 0.7874 -0.4064)
			(stroke
				(width 0.1524)
				(type default)
			)
			(layer "F.SilkS")
		)
		(fp_line
			(start -0.7874 0.4064)
			(end -0.7874 -0.4064)
			(stroke
				(width 0.1524)
				(type default)
			)
			(layer "F.SilkS")
		)
		(fp_line
			(start 0.7874 -0.4064)
			(end 0.7874 0.4064)
			(stroke
				(width 0.1524)
				(type default)
			)
			(layer "F.SilkS")
		)
		(fp_line
			(start 0.7874 0.4064)
			(end -0.7874 0.4064)
			(stroke
				(width 0.1524)
				(type default)
			)
			(layer "F.SilkS")
		)
		(fp_line
			(start -0.67945 -0.305054)
			(end -0.12065 -0.305054)
			(stroke
				(width 0.1)
				(type default)
			)
			(layer "F.Fab")
		)
		(fp_line
			(start -0.67945 0.3048)
			(end -0.67945 -0.305054)
			(stroke
				(width 0.1)
				(type default)
			)
			(layer "F.Fab")
		)
		(fp_line
			(start -0.12065 -0.305054)
			(end -0.12065 -0.2794)
			(stroke
				(width 0.1)
				(type default)
			)
			(layer "F.Fab")
		)
		(fp_line
			(start -0.12065 -0.2794)
			(end 0.12065 -0.2794)
			(stroke
				(width 0.1)
				(type default)
			)
			(layer "F.Fab")
		)
		(fp_line
			(start -0.12065 0.2794)
			(end -0.12065 0.3048)
			(stroke
				(width 0.1)
				(type default)
			)
			(layer "F.Fab")
		)
		(fp_line
			(start -0.12065 0.3048)
			(end -0.67945 0.3048)
			(stroke
				(width 0.1)
				(type default)
			)
			(layer "F.Fab")
		)
		(fp_line
			(start 0.120396 0.2794)
			(end -0.12065 0.2794)
			(stroke
				(width 0.1)
				(type default)
			)
			(layer "F.Fab")
		)
		(fp_line
			(start 0.120396 0.3048)
			(end 0.120396 0.2794)
			(stroke
				(width 0.1)
				(type default)
			)
			(layer "F.Fab")
		)
		(fp_line
			(start 0.12065 -0.3048)
			(end 0.67945 -0.3048)
			(stroke
				(width 0.1)
				(type default)
			)
			(layer "F.Fab")
		)
		(fp_line
			(start 0.12065 -0.2794)
			(end 0.12065 -0.3048)
			(stroke
				(width 0.1)
				(type default)
			)
			(layer "F.Fab")
		)
		(fp_line
			(start 0.67945 -0.3048)
			(end 0.67945 0.3048)
			(stroke
				(width 0.1)
				(type default)
			)
			(layer "F.Fab")
		)
		(fp_line
			(start 0.67945 0.3048)
			(end 0.120396 0.3048)
			(stroke
				(width 0.1)
				(type default)
			)
			(layer "F.Fab")
		)
		(pad "1" smd circle
			(at -0.40005 0)
			(size 0 0)
			(layers "F.Cu" "F.Mask" "F.Paste")
			(net "RST_PLTRST_PLD_B_N")
		)
		(pad "2" smd circle
			(at 0.40005 0)
			(size 0 0)
			(layers "F.Cu" "F.Mask" "F.Paste")
			(net "GND")
		)
	)
	(footprint ""
		(layer "F.Cu")
		(at 217.881962 -68.340478)
		(property "Reference" "PR3963"
			(at 0 0 0)
			(layer "F.SilkS")
			(hide yes)
			(effects
				(font
					(size 1.27 1.27)
				)
			)
		)
		(property "Value" ""
			(at 0 0 0)
			(layer "F.Fab")
			(effects
				(font
					(size 1.27 1.27)
				)
			)
		)
		(duplicate_pad_numbers_are_jumpers no)
		(fp_line
			(start -0.7874 -0.4064)
			(end 0.7874 -0.4064)
			(stroke
				(width 0.1524)
				(type default)
			)
			(layer "F.SilkS")
		)
		(fp_line
			(start -0.7874 0.4064)
			(end -0.7874 -0.4064)
			(stroke
				(width 0.1524)
				(type default)
			)
			(layer "F.SilkS")
		)
		(fp_line
			(start 0.7874 -0.4064)
			(end 0.7874 0.4064)
			(stroke
				(width 0.1524)
				(type default)
			)
			(layer "F.SilkS")
		)
		(fp_line
			(start 0.7874 0.4064)
			(end -0.7874 0.4064)
			(stroke
				(width 0.1524)
				(type default)
			)
			(layer "F.SilkS")
		)
		(fp_line
			(start -0.67945 -0.305054)
			(end -0.12065 -0.305054)
			(stroke
				(width 0.1)
				(type default)
			)
			(layer "F.Fab")
		)
		(fp_line
			(start -0.67945 0.3048)
			(end -0.67945 -0.305054)
			(stroke
				(width 0.1)
				(type default)
			)
			(layer "F.Fab")
		)
		(fp_line
			(start -0.12065 -0.305054)
			(end -0.12065 -0.2794)
			(stroke
				(width 0.1)
				(type default)
			)
			(layer "F.Fab")
		)
		(fp_line
			(start -0.12065 -0.2794)
			(end 0.12065 -0.2794)
			(stroke
				(width 0.1)
				(type default)
			)
			(layer "F.Fab")
		)
		(fp_line
			(start -0.12065 0.2794)
			(end -0.12065 0.3048)
			(stroke
				(width 0.1)
				(type default)
			)
			(layer "F.Fab")
		)
		(fp_line
			(start -0.12065 0.3048)
			(end -0.67945 0.3048)
			(stroke
				(width 0.1)
				(type default)
			)
			(layer "F.Fab")
		)
		(fp_line
			(start 0.120396 0.2794)
			(end -0.12065 0.2794)
			(stroke
				(width 0.1)
				(type default)
			)
			(layer "F.Fab")
		)
		(fp_line
			(start 0.120396 0.3048)
			(end 0.120396 0.2794)
			(stroke
				(width 0.1)
				(type default)
			)
			(layer "F.Fab")
		)
		(fp_line
			(start 0.12065 -0.3048)
			(end 0.67945 -0.3048)
			(stroke
				(width 0.1)
				(type default)
			)
			(layer "F.Fab")
		)
		(fp_line
			(start 0.12065 -0.2794)
			(end 0.12065 -0.3048)
			(stroke
				(width 0.1)
				(type default)
			)
			(layer "F.Fab")
		)
		(fp_line
			(start 0.67945 -0.3048)
			(end 0.67945 0.3048)
			(stroke
				(width 0.1)
				(type default)
			)
			(layer "F.Fab")
		)
		(fp_line
			(start 0.67945 0.3048)
			(end 0.120396 0.3048)
			(stroke
				(width 0.1)
				(type default)
			)
			(layer "F.Fab")
		)
		(pad "1" smd circle
			(at -0.40005 0)
			(size 0 0)
			(layers "F.Cu" "F.Mask" "F.Paste")
			(net "P3V3_AUX")
		)
		(pad "2" smd circle
			(at 0.40005 0)
			(size 0 0)
			(layers "F.Cu" "F.Mask" "F.Paste")
			(net "P3V3_E1S_UV_0")
		)
	)
)
